# S9S_MB_2U (Grand Teton) — schematic parts with pin connectivity, parts 4844–5000 of 6093; source: Cadence DE-HDL packaged netlist (pstxprt.dat, pstxnet.dat, pstchip.dat)

R3266  Q_RES  4.7K 1% CHIP  pkg 0402LF  page 166 : 1 = P3V3_AUX ; 2 = FM_P2E_MODE
R3267  Q_RES  68K 1% EMPTY  pkg 0402LF  page 166 : 1 = FM_P2E_FGB ; 2 = GND
R3268  Q_RES  68K 1% EMPTY  pkg 0402LF  page 166 : 1 = FM_P2E_EQA1 ; 2 = GND
R3269  Q_RES  1K 1% EMPTY  pkg 0402LF  page 166 : 1 = P3V3_AUX ; 2 = FM_P2E_FGB
R3270  Q_RES  1K 1% EMPTY  pkg 0402LF  page 166 : 1 = FM_P2E_FGB ; 2 = GND
R3271  Q_RES  1K 1% EMPTY  pkg 0402LF  page 166 : 1 = P3V3_AUX ; 2 = FM_P2E_EQA1
R3272  Q_RES  1K 1% EMPTY  pkg 0402LF  page 166 : 1 = FM_P2E_EQA1 ; 2 = GND
R3273  Q_RES  68K 1% EMPTY  pkg 0402LF  page 166 : 1 = FM_P2E_FGA ; 2 = GND
R3274  Q_RES  68K 1% EMPTY  pkg 0402LF  page 166 : 1 = FM_P2E_EQA0 ; 2 = GND
R3275  Q_RES  1K 1% EMPTY  pkg 0402LF  page 166 : 1 = P3V3_AUX ; 2 = FM_P2E_FGA
R3276  Q_RES  1K 1% EMPTY  pkg 0402LF  page 166 : 1 = FM_P2E_FGA ; 2 = GND
R3277  Q_RES  1K 1% EMPTY  pkg 0402LF  page 166 : 1 = P3V3_AUX ; 2 = FM_P2E_EQA0
R3278  Q_RES  1K 1% CHIP  pkg 0402LF  page 166 : 1 = FM_P2E_EQA0 ; 2 = GND
R3279  Q_RES  68K 1% EMPTY  pkg 0402LF  page 166 : 1 = FM_P2E_EQB1 ; 2 = GND
R3280  Q_RES  1K 1% EMPTY  pkg 0402LF  page 166 : 1 = P3V3_AUX ; 2 = FM_P2E_EQB1
R3281  Q_RES  1K 1% EMPTY  pkg 0402LF  page 166 : 1 = FM_P2E_EQB1 ; 2 = GND
R3282  Q_RES  68K 1% EMPTY  pkg 0402LF  page 166 : 1 = FM_P2E_EQB0 ; 2 = GND
R3283  Q_RES  1K 1% EMPTY  pkg 0402LF  page 166 : 1 = P3V3_AUX ; 2 = FM_P2E_EQB0
R3284  Q_RES  1K 1% CHIP  pkg 0402LF  page 166 : 1 = FM_P2E_EQB0 ; 2 = GND
R3285  Q_RES  68K 1% EMPTY  pkg 0402LF  page 166 : 1 = FM_P2E_SWB ; 2 = GND
R3286  Q_RES  1K 1% EMPTY  pkg 0402LF  page 166 : 1 = P3V3_AUX ; 2 = FM_P2E_SWB
R3287  Q_RES  1K 1% EMPTY  pkg 0402LF  page 166 : 1 = FM_P2E_SWB ; 2 = GND
R3288  Q_RES  68K 1% EMPTY  pkg 0402LF  page 166 : 1 = FM_P2E_SWA ; 2 = GND
R3289  Q_RES  1K 1% EMPTY  pkg 0402LF  page 166 : 1 = P3V3_AUX ; 2 = FM_P2E_SWA
R3290  Q_RES  1K 1% EMPTY  pkg 0402LF  page 166 : 1 = FM_P2E_SWA ; 2 = GND
R3291  Q_RES  4.7K 1% EMPTY  pkg 0402LF  page 166 : 1 = PU_TEST ; 2 = GND
R3292  Q_RES  4.7K 1% CHIP  pkg 0402LF  page 166 : 1 = P3V3_AUX ; 2 = CLK_GEN2_GPU_FPGA_OE_OR_N
R3293  Q_RES  4.7K 1% EMPTY  pkg 0402LF  page 166 : 1 = FM_P2E_MODE ; 2 = GND
R3294  Q_RES  0 5% CHIP  pkg 0402LF  page 190 : 1 = LED_M2_SSD_0_ACT_N ; 2 = LED_HDD_ACTIVITY_N
R3295  Q_RES  4.7K 1% CHIP  pkg 0402LF  page 190 : 1 = P3V3_M2_0 ; 2 = LED_HDD_ACTIVITY_N
R3296  Q_RES  4.7K 1% CHIP  pkg 0402LF  page 190 : 1 = P3V3_AUX ; 2 = HDD_ACTIVITY_BUF
R3297  Q_RES  10K 1% CHIP  pkg 0402LF  page 190 : 1 = LED_HDD_ACTIVITY_B_N ; 2 = GND
R3298  Q_RES  10K 1% CHIP  pkg 0402LF  page 190 : 1 = P3V3_AUX ; 2 = HDD_ACTIVITY_BUF_N
R3301  Q_RES  33.2 1% CHIP  pkg 0402LF  page 190 : 1 = IRQ_LVC3_WAKE_N ; 2 = M2_0_PEWAKE_N
R3302  Q_RES  0 5% EMPTY  pkg 0402LF  page 240 : 1 = TP_PCIE_HPM_TXN<3> ; 2 = FM_PCH_SPKR
R3303  Q_RES  0 5% CHIP  pkg 0402LF  page 165 : 1 = OCP_SFF_PRSNT_ALL_R_N ; 2 = OCP_SFF_PRSNT_ALL_R1_N
R3304  Q_RES  0 5% CHIP  pkg 0402LF  page 165 : 1 = OCP_SFF_PRSNT_ALL_R_N ; 2 = OCP_SFF_PRSNT_ALL_R3_N
R3305  Q_RES  0 5% CHIP  pkg 0402LF  page 165 : 1 = OCP_SFF_RBT_ARB_IN_MUX1 ; 2 = OCP_SFF_RBT_ARB_IN_MUX1_R
R3306  Q_RES  0 5% CHIP  pkg 0402LF  page 165 : 1 = OCP_V3_2_PRSNT_ALL_R_N ; 2 = OCP_V3_2_PRSNT_ALL_R3_N
R3307  Q_RES  0 5% CHIP  pkg 0402LF  page 165 : 1 = OCP_SFF_RBT_ARB_IN_MUX2 ; 2 = OCP_SFF_RBT_ARB_IN_MUX2_R
R3308  Q_RES  0 5% CHIP  pkg 0402LF  page 165 : 1 = OCP_V3_2_PRSNT_ALL_R_N ; 2 = OCP_V3_2_PRSNT_ALL_R1_N
R3315  Q_RES  49.9 1% CHIP  pkg 0402LF  page 151 : 1 = GPU_FPGA_RST_R1_BUF_N ; 2 = GPU_FPGA_RST_R_BUF_N
R3317  Q_RES  4.7K 5% EMPTY  pkg 0402LF  page 151 : 1 = P3V3_AUX ; 2 = GPU_FPGA_RST_R1_BUF_N
R3318  Q_RES  100K 1% EMPTY  pkg 0402LF  page 148 : 1 = P3V3_AUX ; 2 = GPU_FPGA_READY
R3320  Q_RES  4.7K 5% CHIP  pkg 0402LF  page 148 : 1 = P3V3_AUX ; 2 = GPU_FPGA_READY_N
R3321  Q_RES  4.7K 5% CHIP  pkg 0402LF  page 148 : 1 = P3V3_AUX ; 2 = GPU_FPGA_READY_ISO
R3322  Q_RES  4.7K 1% CHIP  pkg 0402LF  page 212 : 1 = P3V3_AUX ; 2 = CLK_GEN2_GPU_FPGA_OE_R2_N
R3324  Q_RES  33.2 1% CHIP  pkg 0402LF  page 213 : 1 = GPU_FPGA_READY_ISO ; 2 = GPU_FPGA_READY_ISO_R
R3325  Q_RES  10K 1% CHIP  pkg 0402LF  page 198 : 1 = FM_PCH_SPKR ; 2 = GND
R3326  Q_RES  0 5% CHIP  pkg 0402LF  page 212 : 1 = GPU_FPGA_READY_N ; 2 = GPU_FPGA_READY_R_N
R3327  Q_RES  0 5% CHIP  pkg 0402LF  page 212 : 1 = CLK_GEN2_GPU_FPGA_OE_N ; 2 = CLK_GEN2_GPU_FPGA_OE_R2_N
R3335  Q_RES  0 5% CHIP  pkg 0402LF  page 212 : 1 = CLK_100M_BMC_RC_DP_R ; 2 = CLK_100M_BMC_RC_DP
R3336  Q_RES  0 5% CHIP  pkg 0402LF  page 212 : 1 = CLK_100M_BMC_RC_DN_R ; 2 = CLK_100M_BMC_RC_DN
R3337  Q_RES  0 5% CHIP  pkg 0402LF  page 212 : 1 = CLK_100M_GPU_FPGA_DP_R ; 2 = CLK_100M_GPU_FPGA_DP
R3338  Q_RES  0 5% CHIP  pkg 0402LF  page 212 : 1 = CLK_100M_GPU_FPGA_DN_R ; 2 = CLK_100M_GPU_FPGA_DN
R3340  Q_RES  33.2 1% CHIP  pkg 0402LF  page 241 : 1 = SMB_HOST_CLK_3V3AUX_SCL ; 2 = SMB_HOST_CLK_GEN2_3V3AUX_SCL
R3341  Q_RES  33.2 1% CHIP  pkg 0402LF  page 241 : 1 = SMB_HOST_CLK_3V3AUX_SDA ; 2 = SMB_HOST_CLK_GEN2_3V3AUX_SDA
R3344  Q_RES  1 1% CHIP  pkg 0603LF  page 217 : 1 = P3V3_AUX ; 2 = P3V3_AUX_FPGA_VCCIO3
R3345  Q_RES  1 1% CHIP  pkg 0603LF  page 217 : 1 = P3V3_AUX ; 2 = P3V3_AUX_FPGA_VCCIO4
R3346  Q_RES  1 1% CHIP  pkg 0603LF  page 217 : 1 = P3V3_AUX ; 2 = P3V3_AUX_FPGA_VCCIO0
R3347  Q_RES  1 1% CHIP  pkg 0603LF  page 217 : 1 = P3V3_AUX ; 2 = P3V3_AUX_FPGA_VCCIO2
R3348  Q_RES  1 1% CHIP  pkg 0603LF  page 217 : 1 = P3V3_AUX ; 2 = P3V3_AUX_FPGA_VCCIO1
R3349  Q_RES  1 1% CHIP  pkg 0603LF  page 217 : 1 = P3V3_AUX ; 2 = P3V3_AUX_FPGA_VCCIO5
R3352  Q_RES  0 5% CHIP  pkg 0402LF  page 207 : 1 = CLK_100M_GPU_1_R_DP ; 2 = CLK_100M_GPU_1_DP
R3353  Q_RES  0 5% CHIP  pkg 0402LF  page 207 : 1 = CLK_100M_GPU_1_R_DN ; 2 = CLK_100M_GPU_1_DN
R3354  Q_RES  0 5% CHIP  pkg 0402LF  page 207 : 1 = CLK_100M_GPU_2_R_DP ; 2 = CLK_100M_GPU_2_DP
R3355  Q_RES  0 5% CHIP  pkg 0402LF  page 207 : 1 = CLK_100M_GPU_2_R_DN ; 2 = CLK_100M_GPU_2_DN
R3362  Q_RES  1K 1% CHIP  pkg 0402LF  page 167 : 1 = PD_P2E_BUF2_ENSMB ; 2 = GND
R3381  Q_RES  1K 1% EMPTY  pkg 0402LF  page 167 : 1 = FM_P2E_BUF2_RXDET ; 2 = GND
R3386  Q_RES  1K 1% CHIP  pkg 0402LF  page 167 : 1 = P3V3_AUX ; 2 = FM_P2E_BUF2_VOD_SEL
R3390  Q_RES  49.9 1% CHIP  pkg 0402LF  page 149 : 1 = GPU_FPGA_BOOT_EN_BUF_R ; 2 = GPU_FPGA_BOOT_EN_BUF
R3391  Q_RES  49.9 1% CHIP  pkg 0402LF  page 149 : 1 = RST_PERST_1_SWB_BUF_R_N ; 2 = RST_PERST_1_SWB_BUF_N
R3392  Q_RES  49.9 1% CHIP  pkg 0402LF  page 149 : 1 = GPU_BASE_STBY_EN_BUF_R ; 2 = GPU_BASE_STBY_EN_BUF
R3393  Q_RES  0 5% CHIP  pkg 0402LF  page 231 : 1 = SMB_IOEXP_3V3AUX_SCL_R ; 2 = SMB_IOEXP_3V3AUX_SCL
R3394  Q_RES  0 5% CHIP  pkg 0402LF  page 231 : 1 = SMB_IOEXP_3V3AUX_SDA_R ; 2 = SMB_IOEXP_3V3AUX_SDA
R3395  Q_RES  2.2K 5% CHIP  pkg 0402LF  page 231 : 1 = P3V3_AUX ; 2 = SMB_INA230_3V3AUX_SCL
R3396  Q_RES  2.2K 5% CHIP  pkg 0402LF  page 231 : 1 = P3V3_AUX ; 2 = SMB_INA230_3V3AUX_SDA
R3397  Q_RES  33.2 1% CHIP  pkg 0402LF  page 150 : 1 = GPU_NVS_PWR_BRAKE_N_R ; 2 = GPU_NVS_PWR_BRAKE_N_BUF
R3428  Q_RES  100K 1% EMPTY  pkg 0402LF  page 147 : 1 = GPU_FPGA_THERM_OVERT_N ; 2 = GND
R3429  Q_RES  100K 1% EMPTY  pkg 0402LF  page 147 : 1 = P3V3_AUX ; 2 = GPU_BASE_HMC_READY
R3430  Q_RES  100K 1% EMPTY  pkg 0402LF  page 147 : 1 = GPU_FPGA_OVERT_N ; 2 = GND
R3431  Q_RES  100K 1% EMPTY  pkg 0402LF  page 147 : 1 = GPU_HMC_PRSNT_N ; 2 = GND
R3432  Q_RES  4.7K 5% CHIP  pkg 0402LF  page 147 : 1 = P3V3_AUX ; 2 = GPU_FPGA_THERM_OVERT
R3433  Q_RES  4.7K 5% CHIP  pkg 0402LF  page 147 : 1 = P3V3_AUX ; 2 = GPU_BASE_HMC_READY_N
R3434  Q_RES  4.7K 5% CHIP  pkg 0402LF  page 147 : 1 = P3V3_AUX ; 2 = GPU_HMC_PRSNT
R3435  Q_RES  4.7K 5% CHIP  pkg 0402LF  page 147 : 1 = P3V3_AUX ; 2 = GPU_FPGA_OVERT
R3436  Q_RES  4.7K 5% CHIP  pkg 0402LF  page 147 : 1 = P3V3_AUX ; 2 = GPU_HMC_PRSNT_ISO_N
R3437  Q_RES  4.7K 5% CHIP  pkg 0402LF  page 147 : 1 = P3V3_AUX ; 2 = GPU_FPGA_OVERT_ISO_N
R3438  Q_RES  4.7K 5% CHIP  pkg 0402LF  page 147 : 1 = P3V3_AUX ; 2 = GPU_BASE_HMC_READY_ISO
R3439  Q_RES  4.7K 5% CHIP  pkg 0402LF  page 147 : 1 = P3V3_AUX ; 2 = GPU_FPGA_THERM_OVERT_ISO_N
R3440  Q_RES  0 5% EMPTY  pkg 0402LF  page 144 : 1 = GPU_BASE_ID0 ; 2 = GND
R3441  Q_RES  0 5% CHIP  pkg 0402LF  page 144 : 1 = GPU_BASE_ID1 ; 2 = GND
R3442  Q_RES  0 5% CHIP  pkg 0402LF  page 144 : 1 = GPU_PEX_STRAP0 ; 2 = GND
R3443  Q_RES  0 5% CHIP  pkg 0402LF  page 144 : 1 = GPU_PEX_STRAP1 ; 2 = GND
R3448  Q_RES  4.7K 5% EMPTY  pkg 0402LF  page 149 : 1 = P3V3_AUX ; 2 = GPU_FPGA_BOOT_EN
R3449  Q_RES  100K 1% CHIP  pkg 0402LF  page 149 : 1 = GPU_FPGA_BOOT_EN ; 2 = GND
R3451  Q_RES  4.7K 5% EMPTY  pkg 0402LF  page 149 : 1 = P3V3_AUX ; 2 = GPU_BASE_STBY_EN
R3452  Q_RES  100K 1% CHIP  pkg 0402LF  page 149 : 1 = GPU_BASE_STBY_EN ; 2 = GND
R3453  Q_RES  100K 1% EMPTY  pkg 0402LF  page 149 : 1 = P3V3_AUX ; 2 = GPU_FPGA_BOOT_EN_BUF_R
R3454  Q_RES  1K 1% CHIP  pkg 0402LF  page 149 : 1 = GPU_FPGA_BOOT_EN_BUF_R ; 2 = GND
R3455  Q_RES  10K 1% CHIP  pkg 0402LF  page 149 : 1 = RST_PERST_1_SWB_BUF_R_N ; 2 = GND
R3456  Q_RES  100K 1% EMPTY  pkg 0402LF  page 149 : 1 = P3V3_AUX ; 2 = GPU_BASE_STBY_EN_BUF_R
R3457  Q_RES  10K 1% CHIP  pkg 0402LF  page 149 : 1 = GPU_BASE_STBY_EN_BUF_R ; 2 = GND
R3458  Q_RES  1 1% CHIP  pkg 0603LF  page 217 : 1 = P3V3_AUX ; 2 = VCC_PLD_CORE
R3459  Q_RES  4.7K 5% CHIP  pkg 0402LF  page 150 : 1 = P3V3_AUX ; 2 = GPU_NVS_PWR_BRAKE_N
R3460  Q_RES  100K 1% EMPTY  pkg 0402LF  page 150 : 1 = GPU_NVS_PWR_BRAKE_N ; 2 = GND
R3461  Q_RES  54.9K 1% CHIP  pkg 0402LF  page 150 : 1 = P3V3_AUX ; 2 = GPU_NVS_PWR_BRAKE_N_R
R3462  Q_RES  100K 1% EMPTY  pkg 0402LF  page 150 : 1 = GPU_NVS_PWR_BRAKE_N_R ; 2 = GND
R3463  Q_RES  54.9K 1% CHIP  pkg 0402LF  page 147 : 1 = GPU_BASE_HMC_READY ; 2 = GND
R3464  Q_RES  54.9K 1% CHIP  pkg 0402LF  page 147 : 1 = P3V3_AUX ; 2 = GPU_FPGA_OVERT_N
R3465  Q_RES  10K 1% CHIP  pkg 0402LF  page 147 : 1 = P3V3_AUX ; 2 = GPU_HMC_PRSNT_N
R3466  Q_RES  10K 1% CHIP  pkg 0402LF  page 149 : 1 = RST_PERST_2_SWB_BUF_R_N ; 2 = GND
R3467  Q_RES  10K 1% CHIP  pkg 0402LF  page 149 : 1 = RST_PERST_0_SWB_BUF_R_N ; 2 = GND
R3468  Q_RES  49.9 1% CHIP  pkg 0402LF  page 149 : 1 = RST_PERST_2_SWB_BUF_R_N ; 2 = RST_PERST_2_SWB_BUF_N
R3469  Q_RES  49.9 1% CHIP  pkg 0402LF  page 149 : 1 = RST_PERST_0_SWB_BUF_R_N ; 2 = RST_PERST_0_SWB_BUF_N
R3470  Q_RES  10K 1% EMPTY  pkg 0402LF  page 147 : 1 = P3V3_AUX ; 2 = GPU_WP_HW_CTRL_N
R3471  Q_RES  10K 1% CHIP  pkg 0402LF  page 147 : 1 = GPU_WP_HW_CTRL_N ; 2 = GND
R3472  Q_RES  0 5% EMPTY  pkg 0402LF  page 147 : 1 = GND ; 2 = GPU_WP_HW_CTRL_ISO
R3473  Q_RES  100K 1% EMPTY  pkg 0402LF  page 147 : 1 = GPU_PRSNT_N ; 2 = GND
R3474  Q_RES  4.7K 5% CHIP  pkg 0402LF  page 147 : 1 = P3V3_AUX ; 2 = GPU_PRSNT
R3475  Q_RES  4.7K 5% CHIP  pkg 0402LF  page 147 : 1 = P3V3_AUX ; 2 = GPU_PRSNT_N_ISO
R3476  Q_RES  33.2 1% CHIP  pkg 0402LF  page 213 : 1 = GPU_FPGA_THERM_OVERT_ISO_N ; 2 = GPU_FPGA_THERM_OVERT_ISO_R_N
R3477  Q_RES  33.2 1% CHIP  pkg 0402LF  page 213 : 1 = GPU_NVS_PWR_BRAKE_N ; 2 = GPU_NVS_PWR_BRAKE_R_N
R3478  Q_RES  33.2 1% CHIP  pkg 0402LF  page 213 : 1 = GPU_FPGA_EROT_RST_N ; 2 = GPU_FPGA_EROT_RST_R_N
R3479  Q_RES  33.2 1% CHIP  pkg 0402LF  page 213 : 1 = GPU_BASE_STBY_EN ; 2 = GPU_BASE_STBY_EN_R
R3480  Q_RES  33.2 1% CHIP  pkg 0402LF  page 213 : 1 = GPU_BASE_HMC_READY_ISO ; 2 = GPU_BASE_HMC_READY_ISO_R
R3481  Q_RES  33.2 1% CHIP  pkg 0402LF  page 213 : 1 = GPU_HMC_PRSNT_ISO_N ; 2 = GPU_HMC_PRSNT_ISO_R_N
R3482  Q_RES  33.2 1% CHIP  pkg 0402LF  page 213 : 1 = GPU_FPGA_BOOT_EN ; 2 = GPU_FPGA_BOOT_EN_R
R3483  Q_RES  33.2 1% CHIP  pkg 0402LF  page 213 : 1 = GPU_FPGA_EROT_RECOV_N ; 2 = GPU_FPGA_EROT_RECOV_R_N
R3484  Q_RES  33.2 1% CHIP  pkg 0402LF  page 213 : 1 = GPU_FPGA_OVERT_ISO_N ; 2 = GPU_FPGA_OVERT_ISO_R_N
R3485  Q_RES  33.2 1% CHIP  pkg 0402LF  page 213 : 1 = GPU_WP_HW_CTRL_N ; 2 = GPU_WP_HW_CTRL_R_N
R3486  Q_RES  33.2 1% CHIP  pkg 0402LF  page 213 : 1 = GPU_PRSNT_N_ISO ; 2 = GPU_PRSNT_N_ISO_R
R3487  Q_RES  10K 1% CHIP  pkg 0402LF  page 147 : 1 = P3V3_AUX ; 2 = GPU_PRSNT_N
R3488  Q_RES  4.7K 5% CHIP  pkg 0402LF  page 150 : 1 = P3V3_AUX ; 2 = GPU_FPGA_EROT_RST_N
R3489  Q_RES  100K 1% EMPTY  pkg 0402LF  page 150 : 1 = GPU_FPGA_EROT_RST_N ; 2 = GND
R3490  Q_RES  4.7K 5% CHIP  pkg 0402LF  page 150 : 1 = P3V3_AUX ; 2 = GPU_FPGA_EROT_RECOV_N
R3491  Q_RES  100K 1% EMPTY  pkg 0402LF  page 150 : 1 = GPU_FPGA_EROT_RECOV_N ; 2 = GND
R3492  Q_RES  54.9K 1% CHIP  pkg 0402LF  page 150 : 1 = P3V3_AUX ; 2 = GPU_FPGA_EROT_RST_BUF_R_N
R3493  Q_RES  100K 1% EMPTY  pkg 0402LF  page 150 : 1 = GPU_FPGA_EROT_RST_BUF_R_N ; 2 = GND
R3494  Q_RES  54.9K 1% CHIP  pkg 0402LF  page 150 : 1 = P3V3_AUX ; 2 = GPU_FPGA_EROT_RECOV_BUF_R_N
R3495  Q_RES  100K 1% EMPTY  pkg 0402LF  page 150 : 1 = GPU_FPGA_EROT_RECOV_BUF_R_N ; 2 = GND
R3496  Q_RES  33.2 1% CHIP  pkg 0402LF  page 150 : 1 = GPU_FPGA_EROT_RST_BUF_R_N ; 2 = GPU_FPGA_EROT_RST_BUF_N
R3497  Q_RES  33.2 1% CHIP  pkg 0402LF  page 150 : 1 = GPU_FPGA_EROT_RECOV_BUF_R_N ; 2 = GPU_FPGA_EROT_RECOV_BUF_N
R3498  Q_RES  54.9K 1% CHIP  pkg 0402LF  page 147 : 1 = P3V3_AUX ; 2 = GPU_FPGA_THERM_OVERT_N
R3499  Q_RES  0 5% CHIP  pkg 0402LF  page 227 : 1 = GPU_BASE_ID1 ; 2 = GPU_BASE_ID1_R
R3500  Q_RES  4.7K 5% CHIP  pkg 0402LF  page 238 : 1 = P3V3_OCP_SFF ; 2 = SMB_OCP_SFF_3V3AUX_BUF_SCL
R3501  Q_RES  4.7K 5% CHIP  pkg 0402LF  page 238 : 1 = P3V3_OCP_SFF ; 2 = SMB_OCP_SFF_3V3AUX_BUF_SDA
R3502  Q_RES  100K 1% EMPTY  pkg 0402LF  page 147 : 1 = GPU_FPGA_EROT_FATALERR_N ; 2 = GND
R3503  Q_RES  4.7K 5% CHIP  pkg 0402LF  page 147 : 1 = P3V3_AUX ; 2 = GPU_FPGA_EROT_FATALERR
R3504  Q_RES  4.7K 5% CHIP  pkg 0402LF  page 147 : 1 = P3V3_AUX ; 2 = GPU_FPGA_EROT_FATALERR_ISO_N
R3505  Q_RES  33.2 1% CHIP  pkg 0402LF  page 213 : 1 = GPU_FPGA_EROT_FATALERR_ISO_N ; 2 = GPU_FPGA_EROT_FATALERR_ISO_R_N
R3506  Q_RES  4.7K 5% EMPTY  pkg 0402LF  page 151 : 1 = P3V3_AUX ; 2 = GPU_FPGA_RST_R_N
R3507  Q_RES  10K 1% CHIP  pkg 0402LF  page 151 : 1 = GPU_FPGA_RST_R_N ; 2 = GND
R3508  Q_RES  54.9K 1% CHIP  pkg 0402LF  page 151 : 1 = FM_GPU_PWR_EN_R1 ; 2 = GND
R3509  Q_RES  10K 1% CHIP  pkg 0402LF  page 151 : 1 = GPU_FPGA_RST_R1_BUF_N ; 2 = GND
R3510  Q_RES  54.9K 1% CHIP  pkg 0402LF  page 148 : 1 = P3V3_AUX ; 2 = FM_SMB_1_ALERT_GPU_N
R3511  Q_RES  54.9K 1% CHIP  pkg 0402LF  page 148 : 1 = GPU_FPGA_READY ; 2 = GND
